(kicad_pcb
	(version 20260206)
	(generator "pcbnew")
	(generator_version "10.0")
	(general
		(thickness 1.6)
		(legacy_teardrops no)
	)
	(paper "A4")
	(title_block
		(title "01162023_DA0F0TEBIF0_F0T_Expander_BD_F_brd_V02_OCP.brd")
		(comment 1 "Grand Teton / footprints 4142-4148 of 9728")
	)
	(layers
		(0 "F.Cu" signal "TOP")
		(4 "In1.Cu" signal "GND")
		(6 "In2.Cu" signal "VCC")
		(8 "In3.Cu" signal "VCC1")
		(10 "In4.Cu" signal "GND1")
		(12 "In5.Cu" signal "IN1")
		(14 "In6.Cu" signal "GND2")
		(16 "In7.Cu" signal "IN2")
		(18 "In8.Cu" signal "GND3")
		(20 "In9.Cu" signal "IN3")
		(22 "In10.Cu" signal "GND4")
		(24 "In11.Cu" signal "IN4")
		(26 "In12.Cu" signal "GND5")
		(28 "In13.Cu" signal "IN5")
		(30 "In14.Cu" signal "GND6")
		(32 "In15.Cu" signal "IN6")
		(34 "In16.Cu" signal "GND7")
		(2 "B.Cu" signal "BOTTOM")
		(9 "F.Adhes" user "F.Adhesive")
		(11 "B.Adhes" user "B.Adhesive")
		(13 "F.Paste" user "Package Geometry/Pastemask Top")
		(15 "B.Paste" user "Package Geometry/Pastemask Bottom")
		(5 "F.SilkS" user "Ref Des/Silkscreen Top")
		(7 "B.SilkS" user "Ref Des/Silkscreen Bottom")
		(1 "F.Mask" user "Board Geometry/Soldermask Top")
		(3 "B.Mask" user "Board Geometry/Soldermask Bottom")
		(17 "Dwgs.User" user "User.Drawings")
		(19 "Cmts.User" user "User.Comments")
		(21 "Eco1.User" user "User.Eco1")
		(23 "Eco2.User" user "User.Eco2")
		(25 "Edge.Cuts" user "Board Geometry/Outline")
		(27 "Margin" user)
		(31 "F.CrtYd" user "Package Geometry/Place Bound Top")
		(29 "B.CrtYd" user "Package Geometry/Place Bound Bottom")
		(35 "F.Fab" user "Ref Des/Assembly Top")
		(33 "B.Fab" user "Ref Des/Assembly Bottom")
	)
	(footprint ""
		(layer "F.Cu")
		(at 104.385872 -272.15846 -90)
		(property "Reference" "PL5"
			(at 4.844034 0.527304 0)
			(unlocked yes)
			(layer "F.SilkS")
			(effects
				(font
					(size 0.7874 0.5842)
					(thickness 0.1524)
				)
			)
		)
		(property "Value" ""
			(at 0 0 270)
			(layer "F.Fab")
			(effects
				(font
					(size 1.27 1.27)
				)
			)
		)
		(duplicate_pad_numbers_are_jumpers no)
		(fp_line
			(start -2.249932 2.249932)
			(end -2.249932 1.3843)
			(stroke
				(width 0.1524)
				(type default)
			)
			(layer "F.SilkS")
		)
		(fp_line
			(start 2.249932 2.249932)
			(end -2.249932 2.249932)
			(stroke
				(width 0.1524)
				(type default)
			)
			(layer "F.SilkS")
		)
		(fp_line
			(start 2.249932 1.3843)
			(end 2.249932 2.249932)
			(stroke
				(width 0.1524)
				(type default)
			)
			(layer "F.SilkS")
		)
		(fp_line
			(start -2.249932 -1.3843)
			(end -2.249932 -2.249932)
			(stroke
				(width 0.1524)
				(type default)
			)
			(layer "F.SilkS")
		)
		(fp_line
			(start -2.249932 -2.249932)
			(end 2.249932 -2.249932)
			(stroke
				(width 0.1524)
				(type default)
			)
			(layer "F.SilkS")
		)
		(fp_line
			(start 2.249932 -2.249932)
			(end 2.249932 -1.3843)
			(stroke
				(width 0.1524)
				(type default)
			)
			(layer "F.SilkS")
		)
		(fp_line
			(start -2.249932 2.249932)
			(end -2.249932 -2.249932)
			(stroke
				(width 0.1)
				(type default)
			)
			(layer "F.Fab")
		)
		(fp_line
			(start 2.249932 2.249932)
			(end -2.249932 2.249932)
			(stroke
				(width 0.1)
				(type default)
			)
			(layer "F.Fab")
		)
		(fp_line
			(start -2.249932 -2.249932)
			(end 2.249932 -2.249932)
			(stroke
				(width 0.1)
				(type default)
			)
			(layer "F.Fab")
		)
		(fp_line
			(start 2.249932 -2.249932)
			(end 2.249932 2.249932)
			(stroke
				(width 0.1)
				(type default)
			)
			(layer "F.Fab")
		)
		(pad "1" smd rect
			(at -1.82499 0 270)
			(size 1.0668 2.5146)
			(layers "F.Cu" "F.Mask" "F.Paste")
			(net "SW_P12V_P0V8_PEX0_FLT")
		)
		(pad "2" smd rect
			(at 1.82499 0 270)
			(size 1.0668 2.5146)
			(layers "F.Cu" "F.Mask" "F.Paste")
			(net "P12V_AUX")
		)
	)
	(footprint ""
		(layer "F.Cu")
		(at 363.474 -209.931)
		(property "Reference" "R4604"
			(at 0 0 0)
			(layer "F.SilkS")
			(hide yes)
			(effects
				(font
					(size 1.27 1.27)
				)
			)
		)
		(property "Value" ""
			(at 0 0 0)
			(layer "F.Fab")
			(effects
				(font
					(size 1.27 1.27)
				)
			)
		)
		(duplicate_pad_numbers_are_jumpers no)
		(fp_line
			(start -0.7874 -0.4064)
			(end 0.7874 -0.4064)
			(stroke
				(width 0.1524)
				(type default)
			)
			(layer "F.SilkS")
		)
		(fp_line
			(start -0.7874 0.4064)
			(end -0.7874 -0.4064)
			(stroke
				(width 0.1524)
				(type default)
			)
			(layer "F.SilkS")
		)
		(fp_line
			(start 0.7874 -0.4064)
			(end 0.7874 0.4064)
			(stroke
				(width 0.1524)
				(type default)
			)
			(layer "F.SilkS")
		)
		(fp_line
			(start 0.7874 0.4064)
			(end -0.7874 0.4064)
			(stroke
				(width 0.1524)
				(type default)
			)
			(layer "F.SilkS")
		)
		(fp_line
			(start -0.67945 -0.305054)
			(end -0.12065 -0.305054)
			(stroke
				(width 0.1)
				(type default)
			)
			(layer "F.Fab")
		)
		(fp_line
			(start -0.67945 0.3048)
			(end -0.67945 -0.305054)
			(stroke
				(width 0.1)
				(type default)
			)
			(layer "F.Fab")
		)
		(fp_line
			(start -0.12065 -0.305054)
			(end -0.12065 -0.2794)
			(stroke
				(width 0.1)
				(type default)
			)
			(layer "F.Fab")
		)
		(fp_line
			(start -0.12065 -0.2794)
			(end 0.12065 -0.2794)
			(stroke
				(width 0.1)
				(type default)
			)
			(layer "F.Fab")
		)
		(fp_line
			(start -0.12065 0.2794)
			(end -0.12065 0.3048)
			(stroke
				(width 0.1)
				(type default)
			)
			(layer "F.Fab")
		)
		(fp_line
			(start -0.12065 0.3048)
			(end -0.67945 0.3048)
			(stroke
				(width 0.1)
				(type default)
			)
			(layer "F.Fab")
		)
		(fp_line
			(start 0.120396 0.2794)
			(end -0.12065 0.2794)
			(stroke
				(width 0.1)
				(type default)
			)
			(layer "F.Fab")
		)
		(fp_line
			(start 0.120396 0.3048)
			(end 0.120396 0.2794)
			(stroke
				(width 0.1)
				(type default)
			)
			(layer "F.Fab")
		)
		(fp_line
			(start 0.12065 -0.3048)
			(end 0.67945 -0.3048)
			(stroke
				(width 0.1)
				(type default)
			)
			(layer "F.Fab")
		)
		(fp_line
			(start 0.12065 -0.2794)
			(end 0.12065 -0.3048)
			(stroke
				(width 0.1)
				(type default)
			)
			(layer "F.Fab")
		)
		(fp_line
			(start 0.67945 -0.3048)
			(end 0.67945 0.3048)
			(stroke
				(width 0.1)
				(type default)
			)
			(layer "F.Fab")
		)
		(fp_line
			(start 0.67945 0.3048)
			(end 0.120396 0.3048)
			(stroke
				(width 0.1)
				(type default)
			)
			(layer "F.Fab")
		)
		(pad "1" smd circle
			(at -0.40005 0)
			(size 0 0)
			(layers "F.Cu" "F.Mask" "F.Paste")
			(net "P3V3_AUX")
		)
		(pad "2" smd circle
			(at 0.40005 0)
			(size 0 0)
			(layers "F.Cu" "F.Mask" "F.Paste")
			(net "RST_PEX_SSD0_PERST_R_N")
		)
	)
	(footprint ""
		(layer "F.Cu")
		(at 140.074142 -179.961286 180)
		(property "Reference" "R1105"
			(at 0 0 180)
			(layer "F.SilkS")
			(hide yes)
			(effects
				(font
					(size 1.27 1.27)
				)
			)
		)
		(property "Value" ""
			(at 0 0 180)
			(layer "F.Fab")
			(effects
				(font
					(size 1.27 1.27)
				)
			)
		)
		(duplicate_pad_numbers_are_jumpers no)
		(fp_line
			(start -0.7874 -0.4064)
			(end 0.7874 -0.4064)
			(stroke
				(width 0.1524)
				(type default)
			)
			(layer "F.SilkS")
		)
		(fp_line
			(start 0.67945 0.3048)
			(end 0.120396 0.3048)
			(stroke
				(width 0.1)
				(type default)
			)
			(layer "F.Fab")
		)
		(fp_line
			(start 0.67945 -0.3048)
			(end 0.67945 0.3048)
			(stroke
				(width 0.1)
				(type default)
			)
			(layer "F.Fab")
		)
		(fp_line
			(start 0.12065 -0.2794)
			(end 0.12065 -0.3048)
			(stroke
				(width 0.1)
				(type default)
			)
			(layer "F.Fab")
		)
		(fp_line
			(start 0.12065 -0.3048)
			(end 0.67945 -0.3048)
			(stroke
				(width 0.1)
				(type default)
			)
			(layer "F.Fab")
		)
		(fp_line
			(start 0.120396 0.3048)
			(end 0.120396 0.2794)
			(stroke
				(width 0.1)
				(type default)
			)
			(layer "F.Fab")
		)
		(fp_line
			(start 0.120396 0.2794)
			(end -0.12065 0.2794)
			(stroke
				(width 0.1)
				(type default)
			)
			(layer "F.Fab")
		)
		(fp_line
			(start -0.12065 0.3048)
			(end -0.67945 0.3048)
			(stroke
				(width 0.1)
				(type default)
			)
			(layer "F.Fab")
		)
		(fp_line
			(start -0.12065 0.2794)
			(end -0.12065 0.3048)
			(stroke
				(width 0.1)
				(type default)
			)
			(layer "F.Fab")
		)
		(fp_line
			(start -0.12065 -0.2794)
			(end 0.12065 -0.2794)
			(stroke
				(width 0.1)
				(type default)
			)
			(layer "F.Fab")
		)
		(fp_line
			(start -0.12065 -0.305054)
			(end -0.12065 -0.2794)
			(stroke
				(width 0.1)
				(type default)
			)
			(layer "F.Fab")
		)
		(fp_line
			(start -0.67945 0.3048)
			(end -0.67945 -0.305054)
			(stroke
				(width 0.1)
				(type default)
			)
			(layer "F.Fab")
		)
		(fp_line
			(start -0.67945 -0.305054)
			(end -0.12065 -0.305054)
			(stroke
				(width 0.1)
				(type default)
			)
			(layer "F.Fab")
		)
		(pad "1" smd circle
			(at -0.40005 0 180)
			(size 0 0)
			(layers "F.Cu" "F.Mask" "F.Paste")
			(net "CLK_100M_DB2000QL_NIC5_R_DP")
		)
		(pad "2" smd circle
			(at 0.40005 0 180)
			(size 0 0)
			(layers "F.Cu" "F.Mask" "F.Paste")
			(net "CLK_100M_DB2000QL_NIC5_DP")
		)
	)
	(footprint ""
		(layer "F.Cu")
		(at 321.21221 -300.64202 -90)
		(property "Reference" "R3976"
			(at 0 0 270)
			(layer "F.SilkS")
			(hide yes)
			(effects
				(font
					(size 1.27 1.27)
				)
			)
		)
		(property "Value" ""
			(at 0 0 270)
			(layer "F.Fab")
			(effects
				(font
					(size 1.27 1.27)
				)
			)
		)
		(duplicate_pad_numbers_are_jumpers no)
		(fp_line
			(start -0.7874 0.4064)
			(end -0.7874 -0.4064)
			(stroke
				(width 0.1524)
				(type default)
			)
			(layer "F.SilkS")
		)
		(fp_line
			(start 0.7874 0.4064)
			(end -0.7874 0.4064)
			(stroke
				(width 0.1524)
				(type default)
			)
			(layer "F.SilkS")
		)
		(fp_line
			(start -0.7874 -0.4064)
			(end 0.7874 -0.4064)
			(stroke
				(width 0.1524)
				(type default)
			)
			(layer "F.SilkS")
		)
		(fp_line
			(start 0.7874 -0.4064)
			(end 0.7874 0.4064)
			(stroke
				(width 0.1524)
				(type default)
			)
			(layer "F.SilkS")
		)
		(fp_line
			(start -0.67945 0.3048)
			(end -0.67945 -0.305054)
			(stroke
				(width 0.1)
				(type default)
			)
			(layer "F.Fab")
		)
		(fp_line
			(start -0.12065 0.3048)
			(end -0.67945 0.3048)
			(stroke
				(width 0.1)
				(type default)
			)
			(layer "F.Fab")
		)
		(fp_line
			(start 0.120396 0.3048)
			(end 0.120396 0.2794)
			(stroke
				(width 0.1)
				(type default)
			)
			(layer "F.Fab")
		)
		(fp_line
			(start 0.67945 0.3048)
			(end 0.120396 0.3048)
			(stroke
				(width 0.1)
				(type default)
			)
			(layer "F.Fab")
		)
		(fp_line
			(start -0.12065 0.2794)
			(end -0.12065 0.3048)
			(stroke
				(width 0.1)
				(type default)
			)
			(layer "F.Fab")
		)
		(fp_line
			(start 0.120396 0.2794)
			(end -0.12065 0.2794)
			(stroke
				(width 0.1)
				(type default)
			)
			(layer "F.Fab")
		)
		(fp_line
			(start -0.12065 -0.2794)
			(end 0.12065 -0.2794)
			(stroke
				(width 0.1)
				(type default)
			)
			(layer "F.Fab")
		)
		(fp_line
			(start 0.12065 -0.2794)
			(end 0.12065 -0.3048)
			(stroke
				(width 0.1)
				(type default)
			)
			(layer "F.Fab")
		)
		(fp_line
			(start 0.12065 -0.3048)
			(end 0.67945 -0.3048)
			(stroke
				(width 0.1)
				(type default)
			)
			(layer "F.Fab")
		)
		(fp_line
			(start 0.67945 -0.3048)
			(end 0.67945 0.3048)
			(stroke
				(width 0.1)
				(type default)
			)
			(layer "F.Fab")
		)
		(fp_line
			(start -0.67945 -0.305054)
			(end -0.12065 -0.305054)
			(stroke
				(width 0.1)
				(type default)
			)
			(layer "F.Fab")
		)
		(fp_line
			(start -0.12065 -0.305054)
			(end -0.12065 -0.2794)
			(stroke
				(width 0.1)
				(type default)
			)
			(layer "F.Fab")
		)
		(pad "1" smd circle
			(at -0.40005 0 270)
			(size 0 0)
			(layers "F.Cu" "F.Mask" "F.Paste")
			(net "I2C0_PEX2_SHPC_SDA")
		)
		(pad "2" smd circle
			(at 0.40005 0 270)
			(size 0 0)
			(layers "F.Cu" "F.Mask" "F.Paste")
			(net "I2C_PEX2_HOST_SDA")
		)
	)
	(footprint ""
		(layer "F.Cu")
		(at 382.410462 -63.652146 180)
		(property "Reference" "R6017"
			(at 0 0 180)
			(layer "F.SilkS")
			(hide yes)
			(effects
				(font
					(size 1.27 1.27)
				)
			)
		)
		(property "Value" ""
			(at 0 0 180)
			(layer "F.Fab")
			(effects
				(font
					(size 1.27 1.27)
				)
			)
		)
		(duplicate_pad_numbers_are_jumpers no)
		(fp_line
			(start 0.7874 0.4064)
			(end -0.7874 0.4064)
			(stroke
				(width 0.1524)
				(type default)
			)
			(layer "F.SilkS")
		)
		(fp_line
			(start 0.7874 -0.4064)
			(end 0.7874 0.4064)
			(stroke
				(width 0.1524)
				(type default)
			)
			(layer "F.SilkS")
		)
		(fp_line
			(start -0.7874 0.4064)
			(end -0.7874 -0.4064)
			(stroke
				(width 0.1524)
				(type default)
			)
			(layer "F.SilkS")
		)
		(fp_line
			(start -0.7874 -0.4064)
			(end 0.7874 -0.4064)
			(stroke
				(width 0.1524)
				(type default)
			)
			(layer "F.SilkS")
		)
		(fp_line
			(start 0.67945 0.3048)
			(end 0.120396 0.3048)
			(stroke
				(width 0.1)
				(type default)
			)
			(layer "F.Fab")
		)
		(fp_line
			(start 0.67945 -0.3048)
			(end 0.67945 0.3048)
			(stroke
				(width 0.1)
				(type default)
			)
			(layer "F.Fab")
		)
		(fp_line
			(start 0.12065 -0.2794)
			(end 0.12065 -0.3048)
			(stroke
				(width 0.1)
				(type default)
			)
			(layer "F.Fab")
		)
		(fp_line
			(start 0.12065 -0.3048)
			(end 0.67945 -0.3048)
			(stroke
				(width 0.1)
				(type default)
			)
			(layer "F.Fab")
		)
		(fp_line
			(start 0.120396 0.3048)
			(end 0.120396 0.2794)
			(stroke
				(width 0.1)
				(type default)
			)
			(layer "F.Fab")
		)
		(fp_line
			(start 0.120396 0.2794)
			(end -0.12065 0.2794)
			(stroke
				(width 0.1)
				(type default)
			)
			(layer "F.Fab")
		)
		(fp_line
			(start -0.12065 0.3048)
			(end -0.67945 0.3048)
			(stroke
				(width 0.1)
				(type default)
			)
			(layer "F.Fab")
		)
		(fp_line
			(start -0.12065 0.2794)
			(end -0.12065 0.3048)
			(stroke
				(width 0.1)
				(type default)
			)
			(layer "F.Fab")
		)
		(fp_line
			(start -0.12065 -0.2794)
			(end 0.12065 -0.2794)
			(stroke
				(width 0.1)
				(type default)
			)
			(layer "F.Fab")
		)
		(fp_line
			(start -0.12065 -0.305054)
			(end -0.12065 -0.2794)
			(stroke
				(width 0.1)
				(type default)
			)
			(layer "F.Fab")
		)
		(fp_line
			(start -0.67945 0.3048)
			(end -0.67945 -0.305054)
			(stroke
				(width 0.1)
				(type default)
			)
			(layer "F.Fab")
		)
		(fp_line
			(start -0.67945 -0.305054)
			(end -0.12065 -0.305054)
			(stroke
				(width 0.1)
				(type default)
			)
			(layer "F.Fab")
		)
		(pad "1" smd circle
			(at -0.40005 0 180)
			(size 0 0)
			(layers "F.Cu" "F.Mask" "F.Paste")
			(net "P5V_AUX")
		)
		(pad "2" smd circle
			(at 0.40005 0 180)
			(size 0 0)
			(layers "F.Cu" "F.Mask" "F.Paste")
			(net "P12V_SSD13_PG_G2")
		)
	)
	(footprint ""
		(layer "F.Cu")
		(at 139.817348 -343.952322 90)
		(property "Reference" "C2263"
			(at 0 0 90)
			(layer "F.SilkS")
			(hide yes)
			(effects
				(font
					(size 1.27 1.27)
				)
			)
		)
		(property "Value" ""
			(at 0 0 90)
			(layer "F.Fab")
			(effects
				(font
					(size 1.27 1.27)
				)
			)
		)
		(duplicate_pad_numbers_are_jumpers no)
		(fp_line
			(start 0.299974 -0.150114)
			(end 0.299974 0.150114)
			(stroke
				(width 0.1)
				(type default)
			)
			(layer "F.Fab")
		)
		(fp_line
			(start -0.299974 -0.150114)
			(end 0.299974 -0.150114)
			(stroke
				(width 0.1)
				(type default)
			)
			(layer "F.Fab")
		)
		(fp_line
			(start 0.299974 0.150114)
			(end -0.299974 0.150114)
			(stroke
				(width 0.1)
				(type default)
			)
			(layer "F.Fab")
		)
		(fp_line
			(start -0.299974 0.150114)
			(end -0.299974 -0.150114)
			(stroke
				(width 0.1)
				(type default)
			)
			(layer "F.Fab")
		)
		(pad "1" smd rect
			(at -0.2667 0 90)
			(size 0.3048 0.381)
			(layers "F.Cu" "F.Mask" "F.Paste")
			(net "P5E_PEX1_STN5_TX_DP<85>")
		)
		(pad "2" smd rect
			(at 0.2667 0 90)
			(size 0.3048 0.381)
			(layers "F.Cu" "F.Mask" "F.Paste")
			(net "P5E_PEX1_STN5_TX_C_DP<85>")
		)
	)
	(footprint ""
		(layer "F.Cu")
		(at 38.782752 -141.87297)
		(property "Reference" "R32"
			(at 0 0 0)
			(layer "F.SilkS")
			(hide yes)
			(effects
				(font
					(size 1.27 1.27)
				)
			)
		)
		(property "Value" ""
			(at 0 0 0)
			(layer "F.Fab")
			(effects
				(font
					(size 1.27 1.27)
				)
			)
		)
		(duplicate_pad_numbers_are_jumpers no)
		(fp_line
			(start -0.7874 -0.4064)
			(end 0.7874 -0.4064)
			(stroke
				(width 0.1524)
				(type default)
			)
			(layer "F.SilkS")
		)
		(fp_line
			(start -0.7874 0.4064)
			(end -0.7874 -0.4064)
			(stroke
				(width 0.1524)
				(type default)
			)
			(layer "F.SilkS")
		)
		(fp_line
			(start 0.7874 -0.4064)
			(end 0.7874 0.4064)
			(stroke
				(width 0.1524)
				(type default)
			)
			(layer "F.SilkS")
		)
		(fp_line
			(start 0.7874 0.4064)
			(end -0.7874 0.4064)
			(stroke
				(width 0.1524)
				(type default)
			)
			(layer "F.SilkS")
		)
		(fp_line
			(start -0.67945 -0.305054)
			(end -0.12065 -0.305054)
			(stroke
				(width 0.1)
				(type default)
			)
			(layer "F.Fab")
		)
		(fp_line
			(start -0.67945 0.3048)
			(end -0.67945 -0.305054)
			(stroke
				(width 0.1)
				(type default)
			)
			(layer "F.Fab")
		)
		(fp_line
			(start -0.12065 -0.305054)
			(end -0.12065 -0.2794)
			(stroke
				(width 0.1)
				(type default)
			)
			(layer "F.Fab")
		)
		(fp_line
			(start -0.12065 -0.2794)
			(end 0.12065 -0.2794)
			(stroke
				(width 0.1)
				(type default)
			)
			(layer "F.Fab")
		)
		(fp_line
			(start -0.12065 0.2794)
			(end -0.12065 0.3048)
			(stroke
				(width 0.1)
				(type default)
			)
			(layer "F.Fab")
		)
		(fp_line
			(start -0.12065 0.3048)
			(end -0.67945 0.3048)
			(stroke
				(width 0.1)
				(type default)
			)
			(layer "F.Fab")
		)
		(fp_line
			(start 0.120396 0.2794)
			(end -0.12065 0.2794)
			(stroke
				(width 0.1)
				(type default)
			)
			(layer "F.Fab")
		)
		(fp_line
			(start 0.120396 0.3048)
			(end 0.120396 0.2794)
			(stroke
				(width 0.1)
				(type default)
			)
			(layer "F.Fab")
		)
		(fp_line
			(start 0.12065 -0.3048)
			(end 0.67945 -0.3048)
			(stroke
				(width 0.1)
				(type default)
			)
			(layer "F.Fab")
		)
		(fp_line
			(start 0.12065 -0.2794)
			(end 0.12065 -0.3048)
			(stroke
				(width 0.1)
				(type default)
			)
			(layer "F.Fab")
		)
		(fp_line
			(start 0.67945 -0.3048)
			(end 0.67945 0.3048)
			(stroke
				(width 0.1)
				(type default)
			)
			(layer "F.Fab")
		)
		(fp_line
			(start 0.67945 0.3048)
			(end 0.120396 0.3048)
			(stroke
				(width 0.1)
				(type default)
			)
			(layer "F.Fab")
		)
		(pad "1" smd circle
			(at -0.40005 0)
			(size 0 0)
			(layers "F.Cu" "F.Mask" "F.Paste")
			(net "NIC0_BIF1_N")
		)
		(pad "2" smd circle
			(at 0.40005 0)
			(size 0 0)
			(layers "F.Cu" "F.Mask" "F.Paste")
			(net "GND")
		)
	)
)
